(kicad_pcb
	(version 20260206)
	(generator "pcbnew")
	(generator_version "10.0")
	(general
		(thickness 1.6)
		(legacy_teardrops no)
	)
	(paper "A4")
	(title_block
		(title "Wiwynn_Tioga_Pass_MB.brd")
		(comment 1 "Tioga Pass / footprints 182-187 of 4770")
	)
	(layers
		(0 "F.Cu" signal "TOP")
		(4 "In1.Cu" signal "L2GND")
		(6 "In2.Cu" signal "L3")
		(8 "In3.Cu" signal "L4GND")
		(10 "In4.Cu" signal "L5")
		(12 "In5.Cu" signal "L6GND")
		(14 "In6.Cu" signal "L7VCC")
		(16 "In7.Cu" signal "L8VCC")
		(18 "In8.Cu" signal "L9GND")
		(20 "In9.Cu" signal "L10")
		(22 "In10.Cu" signal "L11GND")
		(24 "In11.Cu" signal "L12")
		(26 "In12.Cu" signal "L13GND")
		(2 "B.Cu" signal "BOTTOM")
		(9 "F.Adhes" user "F.Adhesive")
		(11 "B.Adhes" user "B.Adhesive")
		(13 "F.Paste" user "Package Geometry/Pastemask Top")
		(15 "B.Paste" user "Package Geometry/Pastemask Bottom")
		(5 "F.SilkS" user "Ref Des/Silkscreen Top")
		(7 "B.SilkS" user "Ref Des/Silkscreen Bottom")
		(1 "F.Mask" user "Board Geometry/Soldermask Top")
		(3 "B.Mask" user "Board Geometry/Soldermask Bottom")
		(17 "Dwgs.User" user "User.Drawings")
		(19 "Cmts.User" user "User.Comments")
		(21 "Eco1.User" user "User.Eco1")
		(23 "Eco2.User" user "User.Eco2")
		(25 "Edge.Cuts" user "Board Geometry/Outline")
		(27 "Margin" user)
		(31 "F.CrtYd" user "Package Geometry/Place Bound Top")
		(29 "B.CrtYd" user "Package Geometry/Place Bound Bottom")
		(35 "F.Fab" user "Ref Des/Assembly Top")
		(33 "B.Fab" user "Ref Des/Assembly Bottom")
	)
	(footprint ""
		(layer "F.Cu")
		(at -2.5146 -125.222)
		(property "Reference" "C1B12"
			(at 0 0 0)
			(layer "F.SilkS")
			(hide yes)
			(effects
				(font
					(size 1.27 1.27)
				)
			)
		)
		(property "Value" ""
			(at 0 0 0)
			(layer "F.Fab")
			(effects
				(font
					(size 1.27 1.27)
				)
			)
		)
		(duplicate_pad_numbers_are_jumpers no)
		(fp_rect
			(start -0.3048 0.9906)
			(end 0.3048 -0.1016)
			(stroke
				(width 0)
				(type default)
			)
			(fill no)
			(layer "F.CrtYd")
		)
		(fp_line
			(start -0.3048 -0.1016)
			(end -0.3048 0.9906)
			(stroke
				(width 0.1)
				(type default)
			)
			(layer "F.Fab")
		)
		(fp_line
			(start -0.3048 0.9906)
			(end 0.3048 0.9906)
			(stroke
				(width 0.1)
				(type default)
			)
			(layer "F.Fab")
		)
		(fp_line
			(start 0.3048 -0.1016)
			(end -0.3048 -0.1016)
			(stroke
				(width 0.1)
				(type default)
			)
			(layer "F.Fab")
		)
		(fp_line
			(start 0.3048 0.9906)
			(end 0.3048 -0.1016)
			(stroke
				(width 0.1)
				(type default)
			)
			(layer "F.Fab")
		)
		(pad "1" smd rect
			(at 0 0)
			(size 0.508 0.508)
			(layers "F.Cu" "F.Mask" "F.Paste")
			(net "VR_PVDDQ_KLM_AVSP")
		)
		(pad "2" smd rect
			(at 0 0.889)
			(size 0.508 0.508)
			(layers "F.Cu" "F.Mask" "F.Paste")
			(net "VSENSE_PVDDQ_KLM_N")
		)
		(zone
			(layer "F.Cu")
			(hatch none 0.5)
			(connect_pads
				(clearance 0)
			)
			(min_thickness 0.25)
			(keepout
				(tracks allowed)
				(vias not_allowed)
				(pads allowed)
				(copperpour not_allowed)
				(footprints allowed)
			)
			(placement
				(enabled no)
				(sheetname "")
			)
			(fill
				(thermal_gap 0.5)
				(thermal_bridge_width 0.5)
				(island_removal_mode 0)
			)
			(polygon
				(pts
					(xy -2.7686 -124.587) (xy -2.2606 -124.587) (xy -2.2606 -124.968) (xy -2.7686 -124.968)
				)
			)
		)
	)
	(footprint ""
		(layer "F.Cu")
		(at 155.194 -30.5308)
		(property "Reference" "R3F1"
			(at 0 0 0)
			(layer "F.SilkS")
			(hide yes)
			(effects
				(font
					(size 1.27 1.27)
				)
			)
		)
		(property "Value" ""
			(at 0 0 0)
			(layer "F.Fab")
			(effects
				(font
					(size 1.27 1.27)
				)
			)
		)
		(duplicate_pad_numbers_are_jumpers no)
		(fp_poly
			(pts
				(xy -0.2794 -0.1016) (xy 0.2794 -0.1016) (xy 0.2794 0.9906) (xy -0.2794 0.9906)
			)
			(stroke
				(width 0)
				(type default)
			)
			(fill no)
			(layer "F.CrtYd")
		)
		(fp_line
			(start -0.2794 -0.1016)
			(end -0.2794 0.9906)
			(stroke
				(width 0.1)
				(type default)
			)
			(layer "F.Fab")
		)
		(fp_line
			(start -0.2794 0.9906)
			(end 0.2794 0.9906)
			(stroke
				(width 0.1)
				(type default)
			)
			(layer "F.Fab")
		)
		(fp_line
			(start 0.2794 -0.1016)
			(end -0.2794 -0.1016)
			(stroke
				(width 0.1)
				(type default)
			)
			(layer "F.Fab")
		)
		(fp_line
			(start 0.2794 0.9906)
			(end 0.2794 -0.1016)
			(stroke
				(width 0.1)
				(type default)
			)
			(layer "F.Fab")
		)
		(pad "1" smd rect
			(at 0 0)
			(size 0.508 0.508)
			(layers "F.Cu" "F.Mask" "F.Paste")
			(net "CLK_322M_156M_CPU1_OSC_VRM_DN")
		)
		(pad "2" smd rect
			(at 0 0.889)
			(size 0.508 0.508)
			(layers "F.Cu" "F.Mask" "F.Paste")
			(net "CLK_156M_OSC_CPU1_HFI_DN")
		)
		(zone
			(layer "F.Cu")
			(hatch none 0.5)
			(connect_pads
				(clearance 0)
			)
			(min_thickness 0.25)
			(keepout
				(tracks allowed)
				(vias not_allowed)
				(pads allowed)
				(copperpour not_allowed)
				(footprints allowed)
			)
			(placement
				(enabled no)
				(sheetname "")
			)
			(fill
				(thermal_gap 0.5)
				(thermal_bridge_width 0.5)
				(island_removal_mode 0)
			)
			(polygon
				(pts
					(xy 154.94 -30.2768) (xy 155.448 -30.2768) (xy 155.448 -29.8958) (xy 154.94 -29.8958)
				)
			)
		)
		(zone
			(layer "F.Cu")
			(hatch none 0.5)
			(connect_pads
				(clearance 0)
			)
			(min_thickness 0.25)
			(keepout
				(tracks not_allowed)
				(vias allowed)
				(pads allowed)
				(copperpour not_allowed)
				(footprints allowed)
			)
			(placement
				(enabled no)
				(sheetname "")
			)
			(fill
				(thermal_gap 0.5)
				(thermal_bridge_width 0.5)
				(island_removal_mode 0)
			)
			(polygon
				(pts
					(xy 154.94 -29.8958) (xy 155.448 -29.8958) (xy 155.448 -30.2768) (xy 154.94 -30.2768)
				)
			)
		)
	)
	(footprint ""
		(layer "F.Cu")
		(at 198.925434 -81.423764 90)
		(property "Reference" "EU4D1"
			(at 3.334766 -1.542034 0)
			(unlocked yes)
			(layer "F.SilkS")
			(effects
				(font
					(size 0.7874 0.5842)
					(thickness 0.1524)
				)
			)
		)
		(property "Value" ""
			(at 0 0 90)
			(layer "F.Fab")
			(effects
				(font
					(size 1.27 1.27)
				)
			)
		)
		(duplicate_pad_numbers_are_jumpers no)
		(fp_line
			(start 2.9718 -3.5052)
			(end 2.9718 3.429)
			(stroke
				(width 0.1524)
				(type default)
			)
			(layer "F.SilkS")
		)
		(fp_line
			(start -3.0099 -3.5052)
			(end 2.9718 -3.5052)
			(stroke
				(width 0.1524)
				(type default)
			)
			(layer "F.SilkS")
		)
		(fp_line
			(start 2.9718 3.429)
			(end -3.0099 3.429)
			(stroke
				(width 0.1524)
				(type default)
			)
			(layer "F.SilkS")
		)
		(fp_line
			(start -3.0099 3.429)
			(end -3.0099 -3.5052)
			(stroke
				(width 0.1524)
				(type default)
			)
			(layer "F.SilkS")
		)
		(fp_circle
			(center -3.057398 -2.678684)
			(end -3.057398 -2.551684)
			(stroke
				(width 0.254)
				(type default)
			)
			(fill no)
			(layer "F.SilkS")
		)
		(fp_poly
			(pts
				(xy -2.9972 -3.4925) (xy -2.9972 -2.6924) (xy -2.1971 -3.4925)
			)
			(stroke
				(width 0)
				(type default)
			)
			(fill yes)
			(layer "F.SilkS")
		)
		(fp_poly
			(pts
				(xy -2.549906 -3.050032) (xy -2.549906 3.050032) (xy 2.549906 3.050032) (xy 2.549906 -3.050032)
			)
			(stroke
				(width 0)
				(type default)
			)
			(fill no)
			(layer "F.CrtYd")
		)
		(fp_line
			(start 2.549906 -3.050032)
			(end 2.549906 3.050032)
			(stroke
				(width 0.1)
				(type default)
			)
			(layer "F.Fab")
		)
		(fp_line
			(start -2.549906 -3.050032)
			(end 2.549906 -3.050032)
			(stroke
				(width 0.1)
				(type default)
			)
			(layer "F.Fab")
		)
		(fp_line
			(start 2.549906 3.050032)
			(end -2.549906 3.050032)
			(stroke
				(width 0.1)
				(type default)
			)
			(layer "F.Fab")
		)
		(fp_line
			(start -2.549906 3.050032)
			(end -2.549906 -3.050032)
			(stroke
				(width 0.1)
				(type default)
			)
			(layer "F.Fab")
		)
		(fp_circle
			(center -3.057398 -2.678684)
			(end -3.057398 -2.551684)
			(stroke
				(width 0.254)
				(type default)
			)
			(fill no)
			(layer "F.Fab")
		)
		(pad "1" smd rect
			(at -2.39522 -2.279904 90)
			(size 0.7112 0.254)
			(layers "F.Cu" "F.Mask" "F.Paste")
			(net "PVCCIN_CPU0")
		)
		(pad "2" smd rect
			(at -2.39522 -1.83007 90)
			(size 0.7112 0.254)
			(layers "F.Cu" "F.Mask" "F.Paste")
			(net "GND")
		)
		(pad "3" smd rect
			(at -2.39522 -1.379982 90)
			(size 0.7112 0.254)
			(layers "F.Cu" "F.Mask" "F.Paste")
			(net "VR_PVCCIN_CPU0_PH4_VCIN")
		)
		(pad "4" smd rect
			(at -2.39522 -0.929894 90)
			(size 0.7112 0.254)
			(layers "F.Cu" "F.Mask" "F.Paste")
			(net "P5V_STBY")
		)
		(pad "5" smd rect
			(at -2.39522 -0.48006 90)
			(size 0.7112 0.254)
			(layers "F.Cu" "F.Mask" "F.Paste")
			(net "GND")
		)
		(pad "6" smd rect
			(at -2.39522 -0.029972 90)
			(size 0.7112 0.254)
			(layers "F.Cu" "F.Mask" "F.Paste")
			(net "TP_PVCCIN_CPU0_PH4_GL_0")
		)
		(pad "7" smd custom
			(at 0.016764 1.145032 90)
			(size 0.53975 0.53975)
			(layers "F.Cu" "F.Mask" "F.Paste")
			(net "GND")
			(options
				(clearance outline)
				(anchor circle)
			)
			(primitives
				(gr_poly
					(pts
						(xy -2.7051 1.0795) (xy -2.7051 -0.3683) (xy -0.9271 -0.3683) (xy -0.9271 -1.0795) (xy 2.7051 -1.0795)
						(xy 2.7051 1.0795)
					)
					(width 0)
					(fill yes)
				)
			)
		)
		(pad "10" smd rect
			(at -0.008382 2.874772 90)
			(size 4.3434 0.6096)
			(layers "F.Cu" "F.Mask" "F.Paste")
			(net "VR_PVCCIN_CPU0_PHASE4")
		)
		(pad "25" smd rect
			(at 1.548384 -1.283208 90)
			(size 2.3368 2.0066)
			(layers "F.Cu" "F.Mask" "F.Paste")
			(net "VR_FET_SW_P12V_STBY_PVCCIN_CPU0")
		)
		(pad "30" smd rect
			(at 2.050034 -2.895092 90)
			(size 0.254 0.7112)
			(layers "F.Cu" "F.Mask" "F.Paste")
			(net "VR_FET_SW_P12V_STBY_PVCCIN_CPU0")
		)
		(pad "31" smd rect
			(at 1.599946 -2.895092 90)
			(size 0.254 0.7112)
			(layers "F.Cu" "F.Mask" "F.Paste")
			(net "Net_364")
		)
		(pad "32" smd rect
			(at 1.150112 -2.895092 90)
			(size 0.254 0.7112)
			(layers "F.Cu" "F.Mask" "F.Paste")
			(net "VR_PVCCIN_CPU0_PH4_PHASE")
		)
		(pad "33" smd rect
			(at 0.700024 -2.895092 90)
			(size 0.254 0.7112)
			(layers "F.Cu" "F.Mask" "F.Paste")
			(net "VR_PVCCIN_CPU0_PH4_BOOT_R")
		)
		(pad "34" smd rect
			(at 0.249936 -2.895092 90)
			(size 0.254 0.7112)
			(layers "F.Cu" "F.Mask" "F.Paste")
			(net "VR_PVCCIN_CPU0_PWM4")
		)
		(pad "35" smd rect
			(at -0.199898 -2.895092 90)
			(size 0.254 0.7112)
			(layers "F.Cu" "F.Mask" "F.Paste")
			(net "P5V_STBY")
		)
		(pad "36" smd rect
			(at -0.649986 -2.895092 90)
			(size 0.254 0.7112)
			(layers "F.Cu" "F.Mask" "F.Paste")
			(net "A_TSENSE_PVCCIN_CPU0")
		)
		(pad "37" smd rect
			(at -1.100074 -2.895092 90)
			(size 0.254 0.7112)
			(layers "F.Cu" "F.Mask" "F.Paste")
			(net "VR_PVCCIN_CPU0_PH4_OCSET")
		)
		(pad "38" smd rect
			(at -1.549908 -2.895092 90)
			(size 0.254 0.7112)
			(layers "F.Cu" "F.Mask" "F.Paste")
			(net "ISENSE_PVCCIN_CPU0_PH4_IMON")
		)
		(pad "39" smd rect
			(at -1.999996 -2.895092 90)
			(size 0.254 0.7112)
			(layers "F.Cu" "F.Mask" "F.Paste")
			(net "VR_PVCCIN_CPU0_AIREF4")
		)
		(pad "40" smd rect
			(at -0.871728 -1.283208 90)
			(size 1.8034 2.0066)
			(layers "F.Cu" "F.Mask" "F.Paste")
			(net "GND")
		)
		(pad "41" smd rect
			(at -1.533906 0.247904 90)
			(size 0.508 0.3556)
			(layers "F.Cu" "F.Mask" "F.Paste")
			(net "TP_PVCCIN_CPU0_PH4_GL_1")
		)
	)
	(footprint ""
		(layer "F.Cu")
		(at 33.229296 -61.298582 90)
		(property "Reference" "C1E25"
			(at 0 0 90)
			(layer "F.SilkS")
			(hide yes)
			(effects
				(font
					(size 1.27 1.27)
				)
			)
		)
		(property "Value" ""
			(at 0 0 90)
			(layer "F.Fab")
			(effects
				(font
					(size 1.27 1.27)
				)
			)
		)
		(duplicate_pad_numbers_are_jumpers no)
		(fp_rect
			(start 0.3048 0.9906)
			(end -0.3048 -0.1016)
			(stroke
				(width 0)
				(type default)
			)
			(fill no)
			(layer "F.CrtYd")
		)
		(fp_line
			(start 0.3048 -0.1016)
			(end -0.3048 -0.1016)
			(stroke
				(width 0.1)
				(type default)
			)
			(layer "F.Fab")
		)
		(fp_line
			(start -0.3048 -0.1016)
			(end -0.3048 0.9906)
			(stroke
				(width 0.1)
				(type default)
			)
			(layer "F.Fab")
		)
		(fp_line
			(start 0.3048 0.9906)
			(end 0.3048 -0.1016)
			(stroke
				(width 0.1)
				(type default)
			)
			(layer "F.Fab")
		)
		(fp_line
			(start -0.3048 0.9906)
			(end 0.3048 0.9906)
			(stroke
				(width 0.1)
				(type default)
			)
			(layer "F.Fab")
		)
		(pad "1" smd rect
			(at 0 0 90)
			(size 0.508 0.508)
			(layers "F.Cu" "F.Mask" "F.Paste")
			(net "P5V_STBY")
		)
		(pad "2" smd rect
			(at 0 0.889 90)
			(size 0.508 0.508)
			(layers "F.Cu" "F.Mask" "F.Paste")
			(net "GND")
		)
		(zone
			(layer "F.Cu")
			(hatch none 0.5)
			(connect_pads
				(clearance 0)
			)
			(min_thickness 0.25)
			(keepout
				(tracks not_allowed)
				(vias allowed)
				(pads allowed)
				(copperpour not_allowed)
				(footprints allowed)
			)
			(placement
				(enabled no)
				(sheetname "")
			)
			(fill
				(thermal_gap 0.5)
				(thermal_bridge_width 0.5)
				(island_removal_mode 0)
			)
			(polygon
				(pts
					(xy 33.864296 -61.552582) (xy 33.483296 -61.552582) (xy 33.483296 -61.044582) (xy 33.864296 -61.044582)
				)
			)
		)
		(zone
			(layer "F.Cu")
			(hatch none 0.5)
			(connect_pads
				(clearance 0)
			)
			(min_thickness 0.25)
			(keepout
				(tracks allowed)
				(vias not_allowed)
				(pads allowed)
				(copperpour not_allowed)
				(footprints allowed)
			)
			(placement
				(enabled no)
				(sheetname "")
			)
			(fill
				(thermal_gap 0.5)
				(thermal_bridge_width 0.5)
				(island_removal_mode 0)
			)
			(polygon
				(pts
					(xy 33.864296 -61.552582) (xy 33.483296 -61.552582) (xy 33.483296 -61.044582) (xy 33.864296 -61.044582)
				)
			)
		)
	)
	(footprint ""
		(layer "F.Cu")
		(at 364.617 -113.792 90)
		(property "Reference" "C7B26"
			(at 0 0 90)
			(layer "F.SilkS")
			(hide yes)
			(effects
				(font
					(size 1.27 1.27)
				)
			)
		)
		(property "Value" ""
			(at 0 0 90)
			(layer "F.Fab")
			(effects
				(font
					(size 1.27 1.27)
				)
			)
		)
		(duplicate_pad_numbers_are_jumpers no)
		(fp_poly
			(pts
				(xy 0.3048 -0.1016) (xy 0.3048 0.9906) (xy -0.3048 0.9906) (xy -0.3048 -0.1016)
			)
			(stroke
				(width 0)
				(type default)
			)
			(fill no)
			(layer "F.CrtYd")
		)
		(fp_line
			(start 0.3048 -0.1016)
			(end -0.3048 -0.1016)
			(stroke
				(width 0.1)
				(type default)
			)
			(layer "F.Fab")
		)
		(fp_line
			(start -0.3048 -0.1016)
			(end -0.3048 0.9906)
			(stroke
				(width 0.1)
				(type default)
			)
			(layer "F.Fab")
		)
		(fp_line
			(start 0.3048 0.9906)
			(end 0.3048 -0.1016)
			(stroke
				(width 0.1)
				(type default)
			)
			(layer "F.Fab")
		)
		(fp_line
			(start -0.3048 0.9906)
			(end 0.3048 0.9906)
			(stroke
				(width 0.1)
				(type default)
			)
			(layer "F.Fab")
		)
		(pad "1" smd rect
			(at 0 0 90)
			(size 0.508 0.508)
			(layers "F.Cu" "F.Mask" "F.Paste")
			(net "DMI_CPU0_PCH_TX_DN<3>")
		)
		(pad "2" smd rect
			(at 0 0.889 90)
			(size 0.508 0.508)
			(layers "F.Cu" "F.Mask" "F.Paste")
			(net "DMI_CPU0_PCH_TX_C_DN<3>")
		)
		(zone
			(layer "F.Cu")
			(hatch none 0.5)
			(connect_pads
				(clearance 0)
			)
			(min_thickness 0.25)
			(keepout
				(tracks allowed)
				(vias not_allowed)
				(pads allowed)
				(copperpour not_allowed)
				(footprints allowed)
			)
			(placement
				(enabled no)
				(sheetname "")
			)
			(fill
				(thermal_gap 0.5)
				(thermal_bridge_width 0.5)
				(island_removal_mode 0)
			)
			(polygon
				(pts
					(xy 364.871 -113.538) (xy 364.871 -114.046) (xy 365.252 -114.046) (xy 365.252 -113.538)
				)
			)
		)
		(zone
			(layer "F.Cu")
			(hatch none 0.5)
			(connect_pads
				(clearance 0)
			)
			(min_thickness 0.25)
			(keepout
				(tracks not_allowed)
				(vias allowed)
				(pads allowed)
				(copperpour not_allowed)
				(footprints allowed)
			)
			(placement
				(enabled no)
				(sheetname "")
			)
			(fill
				(thermal_gap 0.5)
				(thermal_bridge_width 0.5)
				(island_removal_mode 0)
			)
			(polygon
				(pts
					(xy 365.252 -113.538) (xy 365.252 -114.046) (xy 364.871 -114.046) (xy 364.871 -113.538)
				)
			)
		)
	)
	(footprint ""
		(layer "F.Cu")
		(at 169.6212 -7.1247 180)
		(property "Reference" "C4G11"
			(at 0 0 180)
			(layer "F.SilkS")
			(hide yes)
			(effects
				(font
					(size 1.27 1.27)
				)
			)
		)
		(property "Value" ""
			(at 0 0 180)
			(layer "F.Fab")
			(effects
				(font
					(size 1.27 1.27)
				)
			)
		)
		(duplicate_pad_numbers_are_jumpers no)
		(fp_poly
			(pts
				(xy 0.3048 -0.1016) (xy 0.3048 0.9906) (xy -0.3048 0.9906) (xy -0.3048 -0.1016)
			)
			(stroke
				(width 0)
				(type default)
			)
			(fill no)
			(layer "F.CrtYd")
		)
		(fp_line
			(start 0.3048 0.9906)
			(end 0.3048 -0.1016)
			(stroke
				(width 0.1)
				(type default)
			)
			(layer "F.Fab")
		)
		(fp_line
			(start 0.3048 -0.1016)
			(end -0.3048 -0.1016)
			(stroke
				(width 0.1)
				(type default)
			)
			(layer "F.Fab")
		)
		(fp_line
			(start -0.3048 0.9906)
			(end 0.3048 0.9906)
			(stroke
				(width 0.1)
				(type default)
			)
			(layer "F.Fab")
		)
		(fp_line
			(start -0.3048 -0.1016)
			(end -0.3048 0.9906)
			(stroke
				(width 0.1)
				(type default)
			)
			(layer "F.Fab")
		)
		(pad "1" smd rect
			(at 0 0 180)
			(size 0.508 0.508)
			(layers "F.Cu" "F.Mask" "F.Paste")
			(net "VR_COMP_PVPP_GHJ")
		)
		(pad "2" smd rect
			(at 0 0.889 180)
			(size 0.508 0.508)
			(layers "F.Cu" "F.Mask" "F.Paste")
			(net "VR_FB_PVPP_GHJ")
		)
		(zone
			(layer "F.Cu")
			(hatch none 0.5)
			(connect_pads
				(clearance 0)
			)
			(min_thickness 0.25)
			(keepout
				(tracks not_allowed)
				(vias allowed)
				(pads allowed)
				(copperpour not_allowed)
				(footprints allowed)
			)
			(placement
				(enabled no)
				(sheetname "")
			)
			(fill
				(thermal_gap 0.5)
				(thermal_bridge_width 0.5)
				(island_removal_mode 0)
			)
			(polygon
				(pts
					(xy 169.8752 -7.7597) (xy 169.3672 -7.7597) (xy 169.3672 -7.3787) (xy 169.8752 -7.3787)
				)
			)
		)
		(zone
			(layer "F.Cu")
			(hatch none 0.5)
			(connect_pads
				(clearance 0)
			)
			(min_thickness 0.25)
			(keepout
				(tracks allowed)
				(vias not_allowed)
				(pads allowed)
				(copperpour not_allowed)
				(footprints allowed)
			)
			(placement
				(enabled no)
				(sheetname "")
			)
			(fill
				(thermal_gap 0.5)
				(thermal_bridge_width 0.5)
				(island_removal_mode 0)
			)
			(polygon
				(pts
					(xy 169.8752 -7.3787) (xy 169.3672 -7.3787) (xy 169.3672 -7.7597) (xy 169.8752 -7.7597)
				)
			)
		)
	)
)
